# S9S_MB_2U (Grand Teton) — schematic netlist excerpt (pin names and nets, part order shuffled) for the footprints in the layout excerpt that follows; sources: Cadence DE-HDL packaged netlist, KiCad conversion of 03242023_DA0F0TMBIJ0_F0T_Motherboard_J_brd_V01_OCP.brd

R610  Q_RES  10K 1% CHIP  pkg 0402LF  page 199 : A = FM_ESPI_CS_SWIZZLE ; B = GND
R1714  Q_RES  0 5% CHIP  pkg 0402LF  page 301 : A = SMB_SML1_PMBUS_HSC_SDA ; B = SMB_SML1_PMBUS_HSC_R_SDA

(kicad_pcb
	(version 20260206)
	(generator "pcbnew")
	(generator_version "10.0")
	(general
		(thickness 1.6)
		(legacy_teardrops no)
	)
	(paper "A4")
	(title_block
		(title "03242023_DA0F0TMBIJ0_F0T_Motherboard_J_brd_V01_OCP.brd")
		(comment 1 "Grand Teton / footprints 5648-5649 of 6105")
	)
	(layers
		(0 "F.Cu" signal "TOP")
		(4 "In1.Cu" signal "GND")
		(6 "In2.Cu" signal "IN1")
		(8 "In3.Cu" signal "GND1")
		(10 "In4.Cu" signal "IN2")
		(12 "In5.Cu" signal "GND2")
		(14 "In6.Cu" signal "IN3")
		(16 "In7.Cu" signal "GND3")
		(18 "In8.Cu" signal "VCC")
		(20 "In9.Cu" signal "VCC1")
		(22 "In10.Cu" signal "GND4")
		(24 "In11.Cu" signal "IN4")
		(26 "In12.Cu" signal "GND5")
		(28 "In13.Cu" signal "IN5")
		(30 "In14.Cu" signal "GND6")
		(32 "In15.Cu" signal "IN6")
		(34 "In16.Cu" signal "GND7")
		(2 "B.Cu" signal "BOTTOM")
		(9 "F.Adhes" user "F.Adhesive")
		(11 "B.Adhes" user "B.Adhesive")
		(13 "F.Paste" user "Package Geometry/Pastemask Top")
		(15 "B.Paste" user "Package Geometry/Pastemask Bottom")
		(5 "F.SilkS" user "Ref Des/Silkscreen Top")
		(7 "B.SilkS" user "Ref Des/Silkscreen Bottom")
		(1 "F.Mask" user "Board Geometry/Soldermask Top")
		(3 "B.Mask" user "Board Geometry/Soldermask Bottom")
		(17 "Dwgs.User" user "User.Drawings")
		(19 "Cmts.User" user "User.Comments")
		(21 "Eco1.User" user "User.Eco1")
		(23 "Eco2.User" user "User.Eco2")
		(25 "Edge.Cuts" user "Board Geometry/Outline")
		(27 "Margin" user)
		(31 "F.CrtYd" user "Package Geometry/Place Bound Top")
		(29 "B.CrtYd" user "Package Geometry/Place Bound Bottom")
		(35 "F.Fab" user "Ref Des/Assembly Top")
		(33 "B.Fab" user "Ref Des/Assembly Bottom")
	)
	(footprint ""
		(layer "B.Cu")
		(at 180.923692 -408.254708 90)
		(property "Reference" "R1714"
			(at 0 0 90)
			(layer "B.SilkS")
			(hide yes)
			(effects
				(font
					(size 1.27 1.27)
				)
				(justify mirror)
			)
		)
		(property "Value" ""
			(at 0 0 90)
			(layer "B.Fab")
			(effects
				(font
					(size 1.27 1.27)
				)
				(justify mirror)
			)
		)
		(duplicate_pad_numbers_are_jumpers no)
		(fp_line
			(start 0.7874 -0.4064)
			(end -0.7874 -0.4064)
			(stroke
				(width 0.1524)
				(type default)
			)
			(layer "B.SilkS")
		)
		(fp_line
			(start -0.7874 -0.4064)
			(end -0.7874 0.4064)
			(stroke
				(width 0.1524)
				(type default)
			)
			(layer "B.SilkS")
		)
		(fp_line
			(start 0.7874 0.4064)
			(end 0.7874 -0.4064)
			(stroke
				(width 0.1524)
				(type default)
			)
			(layer "B.SilkS")
		)
		(fp_line
			(start -0.7874 0.4064)
			(end 0.7874 0.4064)
			(stroke
				(width 0.1524)
				(type default)
			)
			(layer "B.SilkS")
		)
		(fp_line
			(start 0.67945 -0.305054)
			(end 0.12065 -0.305054)
			(stroke
				(width 0.1)
				(type default)
			)
			(layer "B.Fab")
		)
		(fp_line
			(start 0.12065 -0.305054)
			(end 0.12065 -0.2794)
			(stroke
				(width 0.1)
				(type default)
			)
			(layer "B.Fab")
		)
		(fp_line
			(start -0.12065 -0.3048)
			(end -0.67945 -0.3048)
			(stroke
				(width 0.1)
				(type default)
			)
			(layer "B.Fab")
		)
		(fp_line
			(start -0.67945 -0.3048)
			(end -0.67945 0.3048)
			(stroke
				(width 0.1)
				(type default)
			)
			(layer "B.Fab")
		)
		(fp_line
			(start 0.12065 -0.2794)
			(end -0.12065 -0.2794)
			(stroke
				(width 0.1)
				(type default)
			)
			(layer "B.Fab")
		)
		(fp_line
			(start -0.12065 -0.2794)
			(end -0.12065 -0.3048)
			(stroke
				(width 0.1)
				(type default)
			)
			(layer "B.Fab")
		)
		(fp_line
			(start 0.12065 0.2794)
			(end 0.12065 0.3048)
			(stroke
				(width 0.1)
				(type default)
			)
			(layer "B.Fab")
		)
		(fp_line
			(start -0.120396 0.2794)
			(end 0.12065 0.2794)
			(stroke
				(width 0.1)
				(type default)
			)
			(layer "B.Fab")
		)
		(fp_line
			(start 0.67945 0.3048)
			(end 0.67945 -0.305054)
			(stroke
				(width 0.1)
				(type default)
			)
			(layer "B.Fab")
		)
		(fp_line
			(start 0.12065 0.3048)
			(end 0.67945 0.3048)
			(stroke
				(width 0.1)
				(type default)
			)
			(layer "B.Fab")
		)
		(fp_line
			(start -0.120396 0.3048)
			(end -0.120396 0.2794)
			(stroke
				(width 0.1)
				(type default)
			)
			(layer "B.Fab")
		)
		(fp_line
			(start -0.67945 0.3048)
			(end -0.120396 0.3048)
			(stroke
				(width 0.1)
				(type default)
			)
			(layer "B.Fab")
		)
		(pad "1" smd circle
			(at 0.40005 0 270)
			(size 0 0)
			(layers "B.Cu" "B.Mask" "B.Paste")
			(net "SMB_SML1_PMBUS_HSC_SDA")
		)
		(pad "2" smd circle
			(at -0.40005 0 270)
			(size 0 0)
			(layers "B.Cu" "B.Mask" "B.Paste")
			(net "SMB_SML1_PMBUS_HSC_R_SDA")
		)
	)
	(footprint ""
		(layer "B.Cu")
		(at 329.134978 -28.852622 90)
		(property "Reference" "R610"
			(at 0 0 90)
			(layer "B.SilkS")
			(hide yes)
			(effects
				(font
					(size 1.27 1.27)
				)
				(justify mirror)
			)
		)
		(property "Value" ""
			(at 0 0 90)
			(layer "B.Fab")
			(effects
				(font
					(size 1.27 1.27)
				)
				(justify mirror)
			)
		)
		(duplicate_pad_numbers_are_jumpers no)
		(fp_line
			(start 0.7874 -0.4064)
			(end -0.7874 -0.4064)
			(stroke
				(width 0.1524)
				(type default)
			)
			(layer "B.SilkS")
		)
		(fp_line
			(start -0.7874 -0.4064)
			(end -0.7874 0.4064)
			(stroke
				(width 0.1524)
				(type default)
			)
			(layer "B.SilkS")
		)
		(fp_line
			(start 0.7874 0.4064)
			(end 0.7874 -0.4064)
			(stroke
				(width 0.1524)
				(type default)
			)
			(layer "B.SilkS")
		)
		(fp_line
			(start -0.7874 0.4064)
			(end 0.7874 0.4064)
			(stroke
				(width 0.1524)
				(type default)
			)
			(layer "B.SilkS")
		)
		(fp_line
			(start 0.67945 -0.305054)
			(end 0.12065 -0.305054)
			(stroke
				(width 0.1)
				(type default)
			)
			(layer "B.Fab")
		)
		(fp_line
			(start 0.12065 -0.305054)
			(end 0.12065 -0.2794)
			(stroke
				(width 0.1)
				(type default)
			)
			(layer "B.Fab")
		)
		(fp_line
			(start -0.12065 -0.3048)
			(end -0.67945 -0.3048)
			(stroke
				(width 0.1)
				(type default)
			)
			(layer "B.Fab")
		)
		(fp_line
			(start -0.67945 -0.3048)
			(end -0.67945 0.3048)
			(stroke
				(width 0.1)
				(type default)
			)
			(layer "B.Fab")
		)
		(fp_line
			(start 0.12065 -0.2794)
			(end -0.12065 -0.2794)
			(stroke
				(width 0.1)
				(type default)
			)
			(layer "B.Fab")
		)
		(fp_line
			(start -0.12065 -0.2794)
			(end -0.12065 -0.3048)
			(stroke
				(width 0.1)
				(type default)
			)
			(layer "B.Fab")
		)
		(fp_line
			(start 0.12065 0.2794)
			(end 0.12065 0.3048)
			(stroke
				(width 0.1)
				(type default)
			)
			(layer "B.Fab")
		)
		(fp_line
			(start -0.120396 0.2794)
			(end 0.12065 0.2794)
			(stroke
				(width 0.1)
				(type default)
			)
			(layer "B.Fab")
		)
		(fp_line
			(start 0.67945 0.3048)
			(end 0.67945 -0.305054)
			(stroke
				(width 0.1)
				(type default)
			)
			(layer "B.Fab")
		)
		(fp_line
			(start 0.12065 0.3048)
			(end 0.67945 0.3048)
			(stroke
				(width 0.1)
				(type default)
			)
			(layer "B.Fab")
		)
		(fp_line
			(start -0.120396 0.3048)
			(end -0.120396 0.2794)
			(stroke
				(width 0.1)
				(type default)
			)
			(layer "B.Fab")
		)
		(fp_line
			(start -0.67945 0.3048)
			(end -0.120396 0.3048)
			(stroke
				(width 0.1)
				(type default)
			)
			(layer "B.Fab")
		)
		(pad "1" smd circle
			(at 0.40005 0 270)
			(size 0 0)
			(layers "B.Cu" "B.Mask" "B.Paste")
			(net "FM_ESPI_CS_SWIZZLE")
		)
		(pad "2" smd circle
			(at -0.40005 0 270)
			(size 0 0)
			(layers "B.Cu" "B.Mask" "B.Paste")
			(net "GND")
		)
	)
)
